(kicad_pcb
	(version 20260206)
	(generator "pcbnew")
	(generator_version "10.0")
	(general
		(thickness 1.6)
		(legacy_teardrops no)
	)
	(paper "A4")
	(title_block
		(title "timecard-production-celestica-r4006 — R4006-B0001-02_R01.brd")
		(comment 1 "Time Appliance Project (Time Card) / footprints 321-324 of 1113")
	)
	(layers
		(0 "F.Cu" signal "TOP")
		(4 "In1.Cu" signal "L02_GND1")
		(6 "In2.Cu" signal "L03_SIG1")
		(8 "In3.Cu" signal "L04_GND2")
		(10 "In4.Cu" signal "L05_VCC1")
		(12 "In5.Cu" signal "L06_VCC2")
		(14 "In6.Cu" signal "L07_GND3")
		(16 "In7.Cu" signal "L08_SIG2")
		(18 "In8.Cu" signal "L09_GND4")
		(2 "B.Cu" signal "BOTTOM")
		(9 "F.Adhes" user "F.Adhesive")
		(11 "B.Adhes" user "B.Adhesive")
		(13 "F.Paste" user "Package Geometry/Pastemask Top")
		(15 "B.Paste" user "Package Geometry/Pastemask Bottom")
		(5 "F.SilkS" user "Ref Des/Silkscreen Top")
		(7 "B.SilkS" user "Ref Des/Silkscreen Bottom")
		(1 "F.Mask" user "Board Geometry/Soldermask Top")
		(3 "B.Mask" user "Board Geometry/Soldermask Bottom")
		(17 "Dwgs.User" user "User.Drawings")
		(19 "Cmts.User" user "User.Comments")
		(21 "Eco1.User" user "User.Eco1")
		(23 "Eco2.User" user "User.Eco2")
		(25 "Edge.Cuts" user "Board Geometry/Outline")
		(27 "Margin" user)
		(31 "F.CrtYd" user "Package Geometry/Place Bound Top")
		(29 "B.CrtYd" user "Package Geometry/Place Bound Bottom")
		(35 "F.Fab" user "Ref Des/Assembly Top")
		(33 "B.Fab" user "Ref Des/Assembly Bottom")
	)
	(footprint ""
		(layer "F.Cu")
		(at 117.3734 -99.7458 180)
		(property "Reference" "C79"
			(at -0.2286 1.68783 0)
			(unlocked yes)
			(layer "F.SilkS")
			(effects
				(font
					(size 0.7874 0.5842)
					(thickness 0.1524)
				)
			)
		)
		(property "Value" "VAL*"
			(at 0.0762 3.134106 180)
			(unlocked yes)
			(layer "F.Fab")
			(hide yes)
			(effects
				(font
					(size 0.7874 0.5842)
					(thickness 0.1524)
				)
			)
		)
		(property "Tolerance" "TOL*"
			(at 0.0762 4.048506 180)
			(unlocked yes)
			(layer "Cmts.User")
			(hide yes)
			(effects
				(font
					(size 0.7874 0.5842)
					(thickness 0.1524)
				)
			)
		)
		(property "User Part Number" "PARTNUM*"
			(at 0.1016 5.013706 180)
			(unlocked yes)
			(layer "Cmts.User")
			(hide yes)
			(effects
				(font
					(size 0.7874 0.5842)
					(thickness 0.1524)
				)
			)
		)
		(property "Device Type" "CAPACITOR-G107-0F106-EM,10UF,2A"
			(at 0.0508 2.194306 180)
			(unlocked yes)
			(layer "F.Fab")
			(hide yes)
			(effects
				(font
					(size 0.7874 0.5842)
					(thickness 0.1524)
				)
			)
		)
		(duplicate_pad_numbers_are_jumpers no)
		(fp_line
			(start 1.5748 0.9398)
			(end 1.5748 -0.9398)
			(stroke
				(width 0.1)
				(type default)
			)
			(layer "F.SilkS")
		)
		(fp_line
			(start 1.5748 -0.9398)
			(end -1.5748 -0.9398)
			(stroke
				(width 0.1)
				(type default)
			)
			(layer "F.SilkS")
		)
		(fp_line
			(start -1.5748 0.9398)
			(end 1.5748 0.9398)
			(stroke
				(width 0.1)
				(type default)
			)
			(layer "F.SilkS")
		)
		(fp_line
			(start -1.5748 -0.9398)
			(end -1.5748 0.9398)
			(stroke
				(width 0.1)
				(type default)
			)
			(layer "F.SilkS")
		)
		(fp_poly
			(pts
				(xy 1.5748 0.9398) (xy -1.5748 0.9398) (xy -1.5748 -0.9398) (xy 1.5748 -0.9398)
			)
			(stroke
				(width 0)
				(type default)
			)
			(fill no)
			(layer "F.CrtYd")
		)
		(fp_line
			(start 1.016 0.635)
			(end 1.016 -0.635)
			(stroke
				(width 0.1)
				(type default)
			)
			(layer "F.Fab")
		)
		(fp_line
			(start 1.016 -0.635)
			(end -1.016 -0.635)
			(stroke
				(width 0.1)
				(type default)
			)
			(layer "F.Fab")
		)
		(fp_line
			(start -1.016 0.635)
			(end 1.016 0.635)
			(stroke
				(width 0.1)
				(type default)
			)
			(layer "F.Fab")
		)
		(fp_line
			(start -1.016 -0.635)
			(end -1.016 0.635)
			(stroke
				(width 0.1)
				(type default)
			)
			(layer "F.Fab")
		)
		(pad "1" smd rect
			(at -0.8382 0 180)
			(size 0.9652 1.3716)
			(layers "F.Cu" "F.Mask" "F.Paste")
			(net "XP3R3V_GPS")
		)
		(pad "2" smd rect
			(at 0.8382 0 180)
			(size 0.9652 1.3716)
			(layers "F.Cu" "F.Mask" "F.Paste")
			(net "SG")
		)
		(zone
			(layer "F.Cu")
			(hatch none 0.5)
			(connect_pads
				(clearance 0)
			)
			(min_thickness 0.25)
			(keepout
				(tracks allowed)
				(vias not_allowed)
				(pads allowed)
				(copperpour not_allowed)
				(footprints allowed)
			)
			(placement
				(enabled no)
				(sheetname "")
			)
			(fill
				(thermal_gap 0.5)
				(thermal_bridge_width 0.5)
				(island_removal_mode 0)
			)
			(polygon
				(pts
					(xy 117.1448 -100.3808) (xy 117.1448 -99.1108) (xy 117.602 -99.1108) (xy 117.602 -100.3808)
				)
			)
		)
	)
	(footprint ""
		(layer "F.Cu")
		(at 57.023 -126.746)
		(property "Reference" "SP80"
			(at 0 0 0)
			(layer "F.SilkS")
			(hide yes)
			(effects
				(font
					(size 1.27 1.27)
				)
			)
		)
		(property "Value" ""
			(at 0 0 0)
			(layer "F.Fab")
			(effects
				(font
					(size 1.27 1.27)
				)
			)
		)
		(duplicate_pad_numbers_are_jumpers no)
	)
	(footprint ""
		(layer "F.Cu")
		(at 144.526 -40.894)
		(property "Reference" "C269"
			(at 0.127 1.56337 0)
			(unlocked yes)
			(layer "F.SilkS")
			(effects
				(font
					(size 0.7874 0.5842)
					(thickness 0.1524)
				)
			)
		)
		(property "Value" "VAL*"
			(at 0.0762 3.134106 0)
			(unlocked yes)
			(layer "F.Fab")
			(hide yes)
			(effects
				(font
					(size 0.7874 0.5842)
					(thickness 0.1524)
				)
			)
		)
		(property "Tolerance" "TOL*"
			(at 0.0762 4.048506 0)
			(unlocked yes)
			(layer "Cmts.User")
			(hide yes)
			(effects
				(font
					(size 0.7874 0.5842)
					(thickness 0.1524)
				)
			)
		)
		(property "User Part Number" "PARTNUM*"
			(at 0.1016 5.013706 0)
			(unlocked yes)
			(layer "Cmts.User")
			(hide yes)
			(effects
				(font
					(size 0.7874 0.5842)
					(thickness 0.1524)
				)
			)
		)
		(property "Device Type" "CAPACITOR-G107-0F476-AM,47UF,2A"
			(at 0.0508 2.194306 0)
			(unlocked yes)
			(layer "F.Fab")
			(hide yes)
			(effects
				(font
					(size 0.7874 0.5842)
					(thickness 0.1524)
				)
			)
		)
		(duplicate_pad_numbers_are_jumpers no)
		(fp_line
			(start -1.5748 -0.9398)
			(end -1.5748 0.9398)
			(stroke
				(width 0.1)
				(type default)
			)
			(layer "F.SilkS")
		)
		(fp_line
			(start -1.5748 0.9398)
			(end 1.5748 0.9398)
			(stroke
				(width 0.1)
				(type default)
			)
			(layer "F.SilkS")
		)
		(fp_line
			(start 1.5748 -0.9398)
			(end -1.5748 -0.9398)
			(stroke
				(width 0.1)
				(type default)
			)
			(layer "F.SilkS")
		)
		(fp_line
			(start 1.5748 0.9398)
			(end 1.5748 -0.9398)
			(stroke
				(width 0.1)
				(type default)
			)
			(layer "F.SilkS")
		)
		(fp_rect
			(start -1.5748 0.9398)
			(end 1.5748 -0.9398)
			(stroke
				(width 0)
				(type default)
			)
			(fill no)
			(layer "F.CrtYd")
		)
		(fp_line
			(start -1.016 -0.635)
			(end -1.016 0.635)
			(stroke
				(width 0.1)
				(type default)
			)
			(layer "F.Fab")
		)
		(fp_line
			(start -1.016 0.635)
			(end 1.016 0.635)
			(stroke
				(width 0.1)
				(type default)
			)
			(layer "F.Fab")
		)
		(fp_line
			(start 1.016 -0.635)
			(end -1.016 -0.635)
			(stroke
				(width 0.1)
				(type default)
			)
			(layer "F.Fab")
		)
		(fp_line
			(start 1.016 0.635)
			(end 1.016 -0.635)
			(stroke
				(width 0.1)
				(type default)
			)
			(layer "F.Fab")
		)
		(pad "1" smd rect
			(at -0.8382 0)
			(size 0.9652 1.3716)
			(layers "F.Cu" "F.Mask" "F.Paste")
			(net "XP1R0V_FPGA")
		)
		(pad "2" smd rect
			(at 0.8382 0)
			(size 0.9652 1.3716)
			(layers "F.Cu" "F.Mask" "F.Paste")
			(net "SG")
		)
		(zone
			(layer "F.Cu")
			(hatch none 0.5)
			(connect_pads
				(clearance 0)
			)
			(min_thickness 0.25)
			(keepout
				(tracks not_allowed)
				(vias allowed)
				(pads allowed)
				(copperpour not_allowed)
				(footprints allowed)
			)
			(placement
				(enabled no)
				(sheetname "")
			)
			(fill
				(thermal_gap 0.5)
				(thermal_bridge_width 0.5)
				(island_removal_mode 0)
			)
			(polygon
				(pts
					(xy 144.2974 -40.259) (xy 144.7546 -40.259) (xy 144.7546 -41.529) (xy 144.2974 -41.529)
				)
			)
		)
		(zone
			(layer "F.Cu")
			(hatch none 0.5)
			(connect_pads
				(clearance 0)
			)
			(min_thickness 0.25)
			(keepout
				(tracks allowed)
				(vias not_allowed)
				(pads allowed)
				(copperpour not_allowed)
				(footprints allowed)
			)
			(placement
				(enabled no)
				(sheetname "")
			)
			(fill
				(thermal_gap 0.5)
				(thermal_bridge_width 0.5)
				(island_removal_mode 0)
			)
			(polygon
				(pts
					(xy 144.2974 -40.259) (xy 144.7546 -40.259) (xy 144.7546 -41.529) (xy 144.2974 -41.529)
				)
			)
		)
	)
	(footprint ""
		(layer "F.Cu")
		(at 142.1638 -46.6852 -90)
		(property "Reference" "L5"
			(at 5.32257 3.7846 0)
			(unlocked yes)
			(layer "F.SilkS")
			(effects
				(font
					(size 0.7874 0.5842)
					(thickness 0.1524)
				)
				(justify left)
			)
		)
		(property "Value" "VALUE*"
			(at -3.56489 13.891006 270)
			(unlocked yes)
			(layer "F.Fab")
			(hide yes)
			(effects
				(font
					(size 1.6002 1.1938)
					(thickness 0.000001)
				)
				(justify left)
			)
		)
		(property "Device Type" "INDUCTOR_2-G190-10418-01,1.0UHA"
			(at -2.219706 11.425936 270)
			(unlocked yes)
			(layer "F.Fab")
			(hide yes)
			(effects
				(font
					(size 1.6002 1.1938)
					(thickness 0.000001)
				)
				(justify left)
			)
		)
		(property "User Part Number" "PARTNUM*"
			(at -5.249926 16.101314 270)
			(unlocked yes)
			(layer "Cmts.User")
			(hide yes)
			(effects
				(font
					(size 1.6002 1.1938)
					(thickness 0.000001)
				)
				(justify left)
			)
		)
		(property "Tolerance" "TOL*"
			(at -2.304542 9.300718 270)
			(unlocked yes)
			(layer "Cmts.User")
			(hide yes)
			(effects
				(font
					(size 1.6002 1.1938)
					(thickness 0.000001)
				)
				(justify left)
			)
		)
		(duplicate_pad_numbers_are_jumpers no)
		(fp_line
			(start -4.452366 3.704082)
			(end -4.452366 -3.704082)
			(stroke
				(width 0.1)
				(type default)
			)
			(layer "F.SilkS")
		)
		(fp_line
			(start 4.452112 3.704082)
			(end -4.452366 3.704082)
			(stroke
				(width 0.1)
				(type default)
			)
			(layer "F.SilkS")
		)
		(fp_line
			(start -4.452366 -3.704082)
			(end 4.452112 -3.704082)
			(stroke
				(width 0.1)
				(type default)
			)
			(layer "F.SilkS")
		)
		(fp_line
			(start 4.452112 -3.704082)
			(end 4.452112 3.704082)
			(stroke
				(width 0.1)
				(type default)
			)
			(layer "F.SilkS")
		)
		(fp_rect
			(start -4.706366 3.958082)
			(end 4.706112 -3.958082)
			(stroke
				(width 0)
				(type default)
			)
			(fill no)
			(layer "F.CrtYd")
		)
		(fp_line
			(start -3.79984 3.450082)
			(end 3.79984 3.450082)
			(stroke
				(width 0.1)
				(type default)
			)
			(layer "F.Fab")
		)
		(fp_line
			(start 3.79984 3.450082)
			(end 3.79984 -3.450082)
			(stroke
				(width 0.1)
				(type default)
			)
			(layer "F.Fab")
		)
		(fp_line
			(start -3.79984 -3.450082)
			(end -3.79984 3.450082)
			(stroke
				(width 0.1)
				(type default)
			)
			(layer "F.Fab")
		)
		(fp_line
			(start 3.79984 -3.450082)
			(end -3.79984 -3.450082)
			(stroke
				(width 0.1)
				(type default)
			)
			(layer "F.Fab")
		)
		(fp_text user "1"
			(at -3.44805 -4.0132 0)
			(unlocked yes)
			(layer "F.SilkS")
			(effects
				(font
					(size 0.635 0.4064)
					(thickness 0.1524)
				)
			)
		)
		(fp_text user "2"
			(at 3.79857 -4.5212 0)
			(unlocked yes)
			(layer "F.SilkS")
			(effects
				(font
					(size 0.7874 0.5842)
					(thickness 0.1524)
				)
			)
		)
		(fp_text user "1"
			(at -5.19049 0.16891 90)
			(unlocked yes)
			(layer "F.Fab")
			(effects
				(font
					(size 0.7874 0.5842)
					(thickness 0.1524)
				)
			)
		)
		(fp_text user "2"
			(at 5.190236 0.084074 90)
			(unlocked yes)
			(layer "F.Fab")
			(effects
				(font
					(size 0.7874 0.5842)
					(thickness 0.1524)
				)
			)
		)
		(pad "1" smd rect
			(at -2.725166 0 270)
			(size 2.9464 3.5052)
			(layers "F.Cu" "F.Mask" "F.Paste")
			(net "XP1R0V_SW")
		)
		(pad "2" smd rect
			(at 2.724912 0 270)
			(size 2.9464 3.5052)
			(layers "F.Cu" "F.Mask" "F.Paste")
			(net "XP1R0V_FPGA")
		)
	)
)
